# T6G (Grand Teton) — schematic netlist excerpt (pin names and nets, part order shuffled) for the footprints in the layout excerpt that follows; sources: Cadence DE-HDL packaged netlist, KiCad conversion of 04192023_DAF0TMB3IC0_F0TG_MB_C_brd_V02_OCP.brd

J5  SCONN8_G802M0083150RD3HR  IO  pkg HEADER2X4SXN  page 27
  \1\  = CPU0_XTRIG_R1_L4
  \2\  = GND
  \3\  = CPU0_XTRIG_R1_L5
  \4\  = GND
  \5\  = CPU0_XTRIG_R1_L6
  \6\  = GND
  \7\  = CPU0_XTRIG_R1_L7
  \8\  = GND

C749  Q_CAP_DIFFBUS  DIFF BUS_0.22UF 6.3V 20% X6S  pkg C0201  page 66 : \1\ = P5E_CPU1_P2_TX_C_DP<12> ; \2\ = P5E_CPU1_P2_TX_DP<12>

(kicad_pcb
	(version 20260206)
	(generator "pcbnew")
	(generator_version "10.0")
	(general
		(thickness 1.6)
		(legacy_teardrops no)
	)
	(paper "A4")
	(title_block
		(title "04192023_DAF0TMB3IC0_F0TG_MB_C_brd_V02_OCP.brd")
		(comment 1 "Grand Teton / footprints 3185-3186 of 8354")
	)
	(layers
		(0 "F.Cu" signal "TOP")
		(4 "In1.Cu" signal "GND")
		(6 "In2.Cu" signal "IN1")
		(8 "In3.Cu" signal "GND1")
		(10 "In4.Cu" signal "IN2")
		(12 "In5.Cu" signal "GND2")
		(14 "In6.Cu" signal "IN3")
		(16 "In7.Cu" signal "GND3")
		(18 "In8.Cu" signal "VCC")
		(20 "In9.Cu" signal "VCC1")
		(22 "In10.Cu" signal "GND4")
		(24 "In11.Cu" signal "IN4")
		(26 "In12.Cu" signal "GND5")
		(28 "In13.Cu" signal "IN5")
		(30 "In14.Cu" signal "GND6")
		(32 "In15.Cu" signal "IN6")
		(34 "In16.Cu" signal "GND7")
		(2 "B.Cu" signal "BOTTOM")
		(9 "F.Adhes" user "F.Adhesive")
		(11 "B.Adhes" user "B.Adhesive")
		(13 "F.Paste" user "Package Geometry/Pastemask Top")
		(15 "B.Paste" user "Package Geometry/Pastemask Bottom")
		(5 "F.SilkS" user "Ref Des/Silkscreen Top")
		(7 "B.SilkS" user "Ref Des/Silkscreen Bottom")
		(1 "F.Mask" user "Board Geometry/Soldermask Top")
		(3 "B.Mask" user "Board Geometry/Soldermask Bottom")
		(17 "Dwgs.User" user "User.Drawings")
		(19 "Cmts.User" user "User.Comments")
		(21 "Eco1.User" user "User.Eco1")
		(23 "Eco2.User" user "User.Eco2")
		(25 "Edge.Cuts" user "Board Geometry/Outline")
		(27 "Margin" user)
		(31 "F.CrtYd" user "Package Geometry/Place Bound Top")
		(29 "B.CrtYd" user "Package Geometry/Place Bound Bottom")
		(35 "F.Fab" user "Ref Des/Assembly Top")
		(33 "B.Fab" user "Ref Des/Assembly Bottom")
	)
	(footprint ""
		(layer "F.Cu")
		(at 164.740844 -370.57203 -90)
		(property "Reference" "C749"
			(at 0 0 270)
			(layer "F.SilkS")
			(hide yes)
			(effects
				(font
					(size 1.27 1.27)
				)
			)
		)
		(property "Value" ""
			(at 0 0 270)
			(layer "F.Fab")
			(effects
				(font
					(size 1.27 1.27)
				)
			)
		)
		(duplicate_pad_numbers_are_jumpers no)
		(fp_line
			(start -0.299974 0.150114)
			(end -0.299974 -0.150114)
			(stroke
				(width 0.1)
				(type default)
			)
			(layer "F.Fab")
		)
		(fp_line
			(start 0.299974 0.150114)
			(end -0.299974 0.150114)
			(stroke
				(width 0.1)
				(type default)
			)
			(layer "F.Fab")
		)
		(fp_line
			(start -0.299974 -0.150114)
			(end 0.299974 -0.150114)
			(stroke
				(width 0.1)
				(type default)
			)
			(layer "F.Fab")
		)
		(fp_line
			(start 0.299974 -0.150114)
			(end 0.299974 0.150114)
			(stroke
				(width 0.1)
				(type default)
			)
			(layer "F.Fab")
		)
		(pad "1" smd rect
			(at -0.2667 0 270)
			(size 0.3048 0.381)
			(layers "F.Cu" "F.Mask" "F.Paste")
			(net "P5E_CPU1_P2_TX_C_DP<12>")
		)
		(pad "2" smd rect
			(at 0.2667 0 270)
			(size 0.3048 0.381)
			(layers "F.Cu" "F.Mask" "F.Paste")
			(net "P5E_CPU1_P2_TX_DP<12>")
		)
	)
	(footprint ""
		(layer "F.Cu")
		(at 342.799924 -61.999876 180)
		(property "Reference" "J5"
			(at 4.821428 -2.025904 0)
			(unlocked yes)
			(layer "F.SilkS")
			(effects
				(font
					(size 0.7874 0.5842)
					(thickness 0.1524)
				)
			)
		)
		(property "Value" ""
			(at 0 0 180)
			(layer "F.Fab")
			(effects
				(font
					(size 1.27 1.27)
				)
			)
		)
		(duplicate_pad_numbers_are_jumpers no)
		(fp_line
			(start 1.700022 2.739898)
			(end -1.700022 2.739898)
			(stroke
				(width 0.1524)
				(type default)
			)
			(layer "F.SilkS")
		)
		(fp_line
			(start 1.700022 2.4257)
			(end 1.700022 2.739898)
			(stroke
				(width 0.1524)
				(type default)
			)
			(layer "F.SilkS")
		)
		(fp_line
			(start 1.700022 1.1557)
			(end 1.700022 1.3843)
			(stroke
				(width 0.1524)
				(type default)
			)
			(layer "F.SilkS")
		)
		(fp_line
			(start 1.700022 -0.1143)
			(end 1.700022 0.1143)
			(stroke
				(width 0.1524)
				(type default)
			)
			(layer "F.SilkS")
		)
		(fp_line
			(start 1.700022 -1.3843)
			(end 1.700022 -1.1557)
			(stroke
				(width 0.1524)
				(type default)
			)
			(layer "F.SilkS")
		)
		(fp_line
			(start 1.700022 -2.739898)
			(end 1.700022 -2.4257)
			(stroke
				(width 0.1524)
				(type default)
			)
			(layer "F.SilkS")
		)
		(fp_line
			(start -1.700022 2.739898)
			(end -1.700022 2.4257)
			(stroke
				(width 0.1524)
				(type default)
			)
			(layer "F.SilkS")
		)
		(fp_line
			(start -1.700022 1.3843)
			(end -1.700022 1.1557)
			(stroke
				(width 0.1524)
				(type default)
			)
			(layer "F.SilkS")
		)
		(fp_line
			(start -1.700022 0.1143)
			(end -1.700022 -0.1143)
			(stroke
				(width 0.1524)
				(type default)
			)
			(layer "F.SilkS")
		)
		(fp_line
			(start -1.700022 -1.1557)
			(end -1.700022 -1.3843)
			(stroke
				(width 0.1524)
				(type default)
			)
			(layer "F.SilkS")
		)
		(fp_line
			(start -1.700022 -2.4257)
			(end -1.700022 -2.739898)
			(stroke
				(width 0.1524)
				(type default)
			)
			(layer "F.SilkS")
		)
		(fp_line
			(start -1.700022 -2.739898)
			(end 1.700022 -2.739898)
			(stroke
				(width 0.1524)
				(type default)
			)
			(layer "F.SilkS")
		)
		(fp_poly
			(pts
				(xy -3.383534 -1.905) (xy -4.399534 -1.397) (xy -4.399534 -2.413)
			)
			(stroke
				(width 0)
				(type default)
			)
			(fill yes)
			(layer "F.SilkS")
		)
		(fp_line
			(start 1.700022 2.739898)
			(end -1.700022 2.739898)
			(stroke
				(width 0.1)
				(type default)
			)
			(layer "F.Fab")
		)
		(fp_line
			(start 1.700022 -2.739898)
			(end 1.700022 2.739898)
			(stroke
				(width 0.1)
				(type default)
			)
			(layer "F.Fab")
		)
		(fp_line
			(start -1.700022 2.739898)
			(end -1.700022 -2.739898)
			(stroke
				(width 0.1)
				(type default)
			)
			(layer "F.Fab")
		)
		(fp_line
			(start -1.700022 -2.739898)
			(end 1.700022 -2.739898)
			(stroke
				(width 0.1)
				(type default)
			)
			(layer "F.Fab")
		)
		(fp_poly
			(pts
				(xy -4.399534 -2.413) (xy -4.399534 -1.397) (xy -3.383534 -1.905)
			)
			(stroke
				(width 0)
				(type default)
			)
			(fill yes)
			(layer "F.Fab")
		)
		(pad "1" smd rect
			(at -2.050034 -1.905 90)
			(size 0.762 2.413)
			(layers "F.Cu" "F.Mask" "F.Paste")
			(net "CPU0_XTRIG_R1_L4")
		)
		(pad "2" smd rect
			(at 2.050034 -1.905 90)
			(size 0.762 2.413)
			(layers "F.Cu" "F.Mask" "F.Paste")
			(net "GND")
		)
		(pad "3" smd rect
			(at -2.050034 -0.635 90)
			(size 0.762 2.413)
			(layers "F.Cu" "F.Mask" "F.Paste")
			(net "CPU0_XTRIG_R1_L5")
		)
		(pad "4" smd rect
			(at 2.050034 -0.635 90)
			(size 0.762 2.413)
			(layers "F.Cu" "F.Mask" "F.Paste")
			(net "GND")
		)
		(pad "5" smd rect
			(at -2.050034 0.635 90)
			(size 0.762 2.413)
			(layers "F.Cu" "F.Mask" "F.Paste")
			(net "CPU0_XTRIG_R1_L6")
		)
		(pad "6" smd rect
			(at 2.050034 0.635 90)
			(size 0.762 2.413)
			(layers "F.Cu" "F.Mask" "F.Paste")
			(net "GND")
		)
		(pad "7" smd rect
			(at -2.050034 1.905 90)
			(size 0.762 2.413)
			(layers "F.Cu" "F.Mask" "F.Paste")
			(net "CPU0_XTRIG_R1_L7")
		)
		(pad "8" smd rect
			(at 2.050034 1.905 90)
			(size 0.762 2.413)
			(layers "F.Cu" "F.Mask" "F.Paste")
			(net "GND")
		)
	)
)
